FILE_TYPE = MACRO_DRAWING;
SET COLOR_WIRE YELLOW;
SET COLOR_PROP ORANGE;
SET COLOR_DOT WHITE;
SET COLOR_ARC YELLOW;
SET COLOR_BODY GREEN;
SET COLOR_NOTE PURPLE;
SET PROP_DISPLAY VALUE;
SET PAGE_NUMBER P271;
FORCEADD Q_RES..1
(-6225 5300);
FORCEPROP 1 LAST LOCATION R6253
J 0
(-6475 5300);
DISPLAY 0.787234 (-6475 5300);
FORCEPROP 2 LAST $SEC 1
J 0
(-6275 5500);
DISPLAY 0.680851 (-6275 5500);
PAINT MONO (-6275 5500);
DISPLAY INVISIBLE (-6275 5500);
FORCEPROP 2 LAST CDS_SEC 1
J 0
(-6275 5500);
DISPLAY 1.021277 (-6275 5500);
DISPLAY INVISIBLE (-6275 5500);
FORCEPROP 1 LASTPIN (-6325 5300) $PN 1
J 0
(-6313 5312);
DISPLAY 0.787234 (-6313 5312);
FORCEPROP 1 LASTPIN (-6125 5300) $PN 2
J 0
(-6163 5312);
DISPLAY 0.787234 (-6163 5312);
FORCEPROP 1 LAST MATERIAL CHIP
J 0
(-5925 5300);
DISPLAY 0.510638 (-5925 5300);
FORCEPROP 1 LAST TOLERANCE 1%
J 0
(-6000 5300);
DISPLAY 0.510638 (-6000 5300);
FORCEPROP 1 LAST VALUE 33.2
J 2
(-6025 5300);
DISPLAY 0.510638 (-6025 5300);
FORCEPROP 1 LAST WATTAGE 1/16W
J 2
(-6025 5400);
DISPLAY 0.638298 (-6025 5400);
DISPLAY INVISIBLE (-6025 5400);
FORCEPROP 1 LAST PACK_TYPE 0402LF
J 0
(-5875 5300);
DISPLAY 0.638298 (-5875 5300);
DISPLAY INVISIBLE (-5875 5300);
FORCEPROP 2 LAST CDS_LIB pure_quanta
J 0
(-6225 5300);
PAINT MONO (-6225 5300);
DISPLAY INVISIBLE (-6225 5300);
FORCEPROP 1 LAST PATH I10
J 0
(-6275 5450);
DISPLAY 0.978723 (-6275 5450);
PAINT WHITE (-6275 5450);
DISPLAY INVISIBLE (-6275 5450);
FORCEPROP 1 LAST PART_NUMBER CS03322FB03
J 0
(-6350 5350);
DISPLAY 0.638298 (-6350 5350);
DISPLAY INVISIBLE (-6350 5350);
FORCEADD Q_CAP..1
(-6175 4975);
FORCEPROP 1 LAST LOCATION C6086
J 0
(-6125 5075);
DISPLAY 0.978723 (-6125 5075);
FORCEPROP 0 LAST $SEC 1
J 0
(-6125 5125);
DISPLAY 0.680851 (-6125 5125);
PAINT MONO (-6125 5125);
DISPLAY INVISIBLE (-6125 5125);
FORCEPROP 0 LAST CDS_SEC 1
J 0
(-6125 5125);
DISPLAY 1.021277 (-6125 5125);
DISPLAY INVISIBLE (-6125 5125);
FORCEPROP 1 LASTPIN (-6175 5075) $PN 1
J 0
(-6165 5055);
DISPLAY 0.787234 (-6165 5055);
PAINT MONO (-6165 5055);
FORCEPROP 1 LASTPIN (-6175 4875) $PN 2
J 0
(-6165 4855);
DISPLAY 0.787234 (-6165 4855);
PAINT MONO (-6165 4855);
FORCEPROP 1 LAST VOLTAGE 25V
J 0
(-6125 4975);
DISPLAY 0.638298 (-6125 4975);
FORCEPROP 1 LAST VALUE 0.1UF
J 0
(-6125 5025);
DISPLAY 0.638298 (-6125 5025);
FORCEPROP 1 LAST TOLERANCE 10%
J 0
(-6125 4925);
DISPLAY 0.638298 (-6125 4925);
FORCEPROP 1 LAST PACK_TYPE 0402
J 0
(-6125 4825);
DISPLAY 0.638298 (-6125 4825);
FORCEPROP 1 LAST MATERIAL X7R
J 0
(-6125 4875);
DISPLAY 0.638298 (-6125 4875);
FORCEPROP 2 LAST CDS_LIB pure_quanta
J 0
(-6175 4975);
DISPLAY INVISIBLE (-6175 4975);
FORCEPROP 1 LAST PATH I11
J 0
(-6125 5125);
DISPLAY 0.978723 (-6125 5125);
PAINT WHITE (-6125 5125);
DISPLAY INVISIBLE (-6125 5125);
FORCEPROP 1 LAST PART_NUMBER CH4104K1B00
J 0
(-6125 4825);
DISPLAY 0.808511 (-6125 4825);
DISPLAY INVISIBLE (-6125 4825);
FORCEADD UNIVERSAL_GND..1
(-7575 5475);
FORCEPROP 3 LASTPIN (-7575 5525) SIG_NAME GND\g
J 0
(-7565 5535);
DISPLAY 0.659574 (-7565 5535);
PAINT MONO (-7565 5535);
DISPLAY INVISIBLE (-7565 5535);
FORCEPROP 2 LAST CDS_LIB pure_quanta_power
J 0
(-7575 5475);
DISPLAY INVISIBLE (-7575 5475);
FORCEPROP 1 LAST HDL_POWER GND
J 1
(-7550 5400);
DISPLAY 0.872340 (-7550 5400);
PAINT GREEN (-7550 5400);
DISPLAY INVISIBLE (-7550 5400);
FORCEPROP 1 LAST PATH I13
J 0
(-7500 5475);
DISPLAY 0.872340 (-7500 5475);
PAINT AQUA (-7500 5475);
DISPLAY INVISIBLE (-7500 5475);
FORCEADD Q_RES..1
(-7025 5625);
FORCEPROP 1 LAST LOCATION R6251
J 0
(-7225 5625);
DISPLAY 0.638298 (-7225 5625);
FORCEPROP 0 LAST $SEC 1
J 0
(-7150 5675);
DISPLAY 0.680851 (-7150 5675);
PAINT MONO (-7150 5675);
DISPLAY INVISIBLE (-7150 5675);
FORCEPROP 0 LAST CDS_SEC 1
J 0
(-7150 5675);
DISPLAY 1.021277 (-7150 5675);
DISPLAY INVISIBLE (-7150 5675);
FORCEPROP 1 LASTPIN (-7125 5625) $PN 1
J 0
(-7113 5637);
DISPLAY 0.787234 (-7113 5637);
PAINT MONO (-7113 5637);
FORCEPROP 1 LASTPIN (-6925 5625) $PN 2
J 0
(-6963 5637);
DISPLAY 0.787234 (-6963 5637);
PAINT MONO (-6963 5637);
FORCEPROP 1 LAST WATTAGE 1/16W
J 2
(-6650 5625);
DISPLAY 0.638298 (-6650 5625);
FORCEPROP 1 LAST VALUE 4.7K
J 2
(-6800 5625);
DISPLAY 0.638298 (-6800 5625);
FORCEPROP 1 LAST TOLERANCE 1%
J 0
(-6650 5625);
DISPLAY 0.638298 (-6650 5625);
FORCEPROP 1 LAST MATERIAL EMPTY
J 0
(-6575 5625);
DISPLAY 0.638298 (-6575 5625);
PAINT RED (-6575 5625);
FORCEPROP 1 LAST PACK_TYPE 0402LF
J 0
(-6400 5625);
DISPLAY 0.638298 (-6400 5625);
FORCEPROP 2 LAST CDS_LIB pure_quanta
J 0
(-7025 5625);
DISPLAY INVISIBLE (-7025 5625);
FORCEPROP 1 LAST PATH I14
J 0
(-7075 5775);
DISPLAY 0.978723 (-7075 5775);
PAINT WHITE (-7075 5775);
DISPLAY INVISIBLE (-7075 5775);
FORCEPROP 1 LAST PART_NUMBER CS24702FB06
J 0
(-7525 5625);
DISPLAY 0.510638 (-7525 5625);
DISPLAY INVISIBLE (-7525 5625);
FORCEADD UNIVERSAL_GND..1
(-4000 4700);
FORCEPROP 3 LASTPIN (-4000 4750) SIG_NAME GND\g
J 0
(-3990 4760);
DISPLAY 0.659574 (-3990 4760);
PAINT MONO (-3990 4760);
DISPLAY INVISIBLE (-3990 4760);
FORCEPROP 2 LAST CDS_LIB pure_quanta_power
J 0
(-4000 4700);
DISPLAY INVISIBLE (-4000 4700);
FORCEPROP 1 LAST HDL_POWER GND
J 1
(-3975 4625);
DISPLAY 0.872340 (-3975 4625);
PAINT GREEN (-3975 4625);
DISPLAY INVISIBLE (-3975 4625);
FORCEPROP 1 LAST PATH I18
J 0
(-3925 4700);
DISPLAY 0.872340 (-3925 4700);
PAINT AQUA (-3925 4700);
DISPLAY INVISIBLE (-3925 4700);
FORCEADD UNIVERSAL_GND..1
(-5325 5725);
FORCEPROP 3 LASTPIN (-5325 5775) SIG_NAME GND\g
J 0
(-5315 5785);
DISPLAY 0.659574 (-5315 5785);
PAINT MONO (-5315 5785);
DISPLAY INVISIBLE (-5315 5785);
FORCEPROP 2 LAST CDS_LIB pure_quanta_power
J 0
(-5325 5725);
DISPLAY INVISIBLE (-5325 5725);
FORCEPROP 1 LAST HDL_POWER GND
J 1
(-5300 5650);
DISPLAY 0.872340 (-5300 5650);
PAINT GREEN (-5300 5650);
DISPLAY INVISIBLE (-5300 5650);
FORCEPROP 1 LAST PATH I21
J 0
(-5250 5725);
DISPLAY 0.872340 (-5250 5725);
PAINT AQUA (-5250 5725);
DISPLAY INVISIBLE (-5250 5725);
FORCEADD Q_CAP..1
(-5325 5950);
FORCEPROP 1 LAST LOCATION C6087
J 0
(-5275 6050);
DISPLAY 0.978723 (-5275 6050);
FORCEPROP 0 LAST $SEC 1
J 0
(-5275 6100);
DISPLAY 0.680851 (-5275 6100);
PAINT MONO (-5275 6100);
DISPLAY INVISIBLE (-5275 6100);
FORCEPROP 0 LAST CDS_SEC 1
J 0
(-5275 6100);
DISPLAY 1.021277 (-5275 6100);
DISPLAY INVISIBLE (-5275 6100);
FORCEPROP 1 LASTPIN (-5325 6050) $PN 1
J 0
(-5315 6030);
DISPLAY 0.787234 (-5315 6030);
PAINT MONO (-5315 6030);
FORCEPROP 1 LASTPIN (-5325 5850) $PN 2
J 0
(-5315 5830);
DISPLAY 0.787234 (-5315 5830);
PAINT MONO (-5315 5830);
FORCEPROP 1 LAST PACK_TYPE 0402
J 0
(-5275 5800);
DISPLAY 0.638298 (-5275 5800);
FORCEPROP 1 LAST TOLERANCE 10%
J 0
(-5275 5900);
DISPLAY 0.638298 (-5275 5900);
FORCEPROP 1 LAST VOLTAGE 25V
J 0
(-5275 5950);
DISPLAY 0.638298 (-5275 5950);
FORCEPROP 1 LAST VALUE 0.1UF
J 0
(-5275 6000);
DISPLAY 0.638298 (-5275 6000);
FORCEPROP 1 LAST MATERIAL X7R
J 0
(-5275 5850);
DISPLAY 0.638298 (-5275 5850);
FORCEPROP 2 LAST CDS_LIB pure_quanta
J 0
(-5325 5950);
DISPLAY INVISIBLE (-5325 5950);
FORCEPROP 1 LAST PATH I22
J 0
(-5275 6100);
DISPLAY 0.978723 (-5275 6100);
PAINT WHITE (-5275 6100);
DISPLAY INVISIBLE (-5275 6100);
FORCEPROP 1 LAST PART_NUMBER CH4104K1B00
J 0
(-5275 5800);
DISPLAY 0.808511 (-5275 5800);
DISPLAY INVISIBLE (-5275 5800);
FORCEADD UNIVERSAL_POWER..1
(-5075 6350);
FORCEPROP 3 LASTPIN (-5075 6300) SIG_NAME P3V3_AUX\g
J 0
(-5065 6310);
DISPLAY 0.659574 (-5065 6310);
PAINT MONO (-5065 6310);
DISPLAY INVISIBLE (-5065 6310);
FORCEPROP 1 LAST HDL_POWER P3V3_AUX
J 1
(-5075 6400);
DISPLAY 0.872340 (-5075 6400);
PAINT GREEN (-5075 6400);
FORCEPROP 2 LAST CDS_LIB pure_quanta_power
J 0
(-5075 6350);
DISPLAY INVISIBLE (-5075 6350);
FORCEPROP 1 LAST PATH I23
J 0
(-5025 6375);
DISPLAY 0.872340 (-5025 6375);
PAINT AQUA (-5025 6375);
DISPLAY INVISIBLE (-5025 6375);
FORCEADD Q_RES..2
(-3375 6050);
FORCEPROP 1 LAST LOCATION R6247
J 0
(-3330 6175);
DISPLAY 0.978723 (-3330 6175);
FORCEPROP 0 LAST $SEC 1
J 0
(-3325 6225);
DISPLAY 0.680851 (-3325 6225);
PAINT MONO (-3325 6225);
DISPLAY INVISIBLE (-3325 6225);
FORCEPROP 0 LAST CDS_SEC 1
J 0
(-3325 6225);
DISPLAY 1.021277 (-3325 6225);
DISPLAY INVISIBLE (-3325 6225);
FORCEPROP 1 LASTPIN (-3375 6150) $PN 1
J 0
(-3370 6112);
DISPLAY 0.787234 (-3370 6112);
PAINT MONO (-3370 6112);
FORCEPROP 1 LASTPIN (-3375 5950) $PN 2
J 0
(-3370 5960);
DISPLAY 0.787234 (-3370 5960);
PAINT MONO (-3370 5960);
FORCEPROP 1 LAST PACK_TYPE 0402LF
J 0
(-3335 5875);
DISPLAY 0.787234 (-3335 5875);
FORCEPROP 1 LAST MATERIAL CHIP
J 0
(-3335 5975);
DISPLAY 0.787234 (-3335 5975);
FORCEPROP 1 LAST WATTAGE 1/16W
J 0
(-3335 6025);
DISPLAY 0.787234 (-3335 6025);
FORCEPROP 1 LAST TOLERANCE 1%
J 0
(-3330 6075);
DISPLAY 0.787234 (-3330 6075);
FORCEPROP 1 LAST VALUE 4.7K
J 0
(-3330 6125);
DISPLAY 0.787234 (-3330 6125);
FORCEPROP 2 LAST CDS_LIB pure_quanta
J 0
(-3375 6050);
DISPLAY INVISIBLE (-3375 6050);
FORCEPROP 1 LAST PATH I25
J 0
(-3325 6225);
DISPLAY 0.978723 (-3325 6225);
PAINT WHITE (-3325 6225);
DISPLAY INVISIBLE (-3325 6225);
FORCEPROP 1 LAST PART_NUMBER CS24702FB06
J 0
(-3335 5925);
DISPLAY 0.787234 (-3335 5925);
DISPLAY INVISIBLE (-3335 5925);
FORCEADD UNIVERSAL_POWER..1
(-3375 6250);
FORCEPROP 3 LASTPIN (-3375 6200) SIG_NAME P3V3_AUX\g
J 0
(-3365 6210);
DISPLAY 0.659574 (-3365 6210);
PAINT MONO (-3365 6210);
DISPLAY INVISIBLE (-3365 6210);
FORCEPROP 1 LAST HDL_POWER P3V3_AUX
J 1
(-3375 6300);
DISPLAY 0.872340 (-3375 6300);
PAINT GREEN (-3375 6300);
FORCEPROP 2 LAST CDS_LIB pure_quanta_power
J 0
(-3375 6250);
DISPLAY INVISIBLE (-3375 6250);
FORCEPROP 1 LAST PATH I26
J 0
(-3325 6275);
DISPLAY 0.872340 (-3325 6275);
PAINT AQUA (-3325 6275);
DISPLAY INVISIBLE (-3325 6275);
FORCEADD ISL28022FRZT..1
(-4575 5350);
FORCEPROP 1 LAST LOCATION U6005
J 0
(-4870 5931);
DISPLAY 0.723404 (-4870 5931);
PAINT GREEN (-4870 5931);
FORCEPROP 2 LAST SEC 1
J 0
(-4850 6075);
DISPLAY 0.680851 (-4850 6075);
PAINT MONO (-4850 6075);
DISPLAY INVISIBLE (-4850 6075);
FORCEPROP 2 LASTPIN (-5025 5450) $PN 2
J 2
(-5035 5460);
DISPLAY 0.680851 (-5035 5460);
PAINT MONO (-5035 5460);
FORCEPROP 2 LASTPIN (-5025 5500) $PN 1
J 2
(-5035 5510);
DISPLAY 0.680851 (-5035 5510);
PAINT MONO (-5035 5510);
FORCEPROP 2 LASTPIN (-4125 5600) $PN 3
J 0
(-4115 5610);
DISPLAY 0.680851 (-4115 5610);
PAINT MONO (-4115 5610);
FORCEPROP 2 LASTPIN (-4125 5150) $PN 10
J 0
(-4115 5160);
DISPLAY 0.680851 (-4115 5160);
PAINT MONO (-4115 5160);
FORCEPROP 2 LASTPIN (-4125 5500) $PN 6
J 0
(-4115 5510);
DISPLAY 0.680851 (-4115 5510);
PAINT MONO (-4115 5510);
FORCEPROP 2 LASTPIN (-4125 5450) $PN 7
J 0
(-4115 5460);
DISPLAY 0.680851 (-4115 5460);
PAINT MONO (-4115 5460);
FORCEPROP 2 LASTPIN (-4125 5400) $PN 8
J 0
(-4115 5410);
DISPLAY 0.680851 (-4115 5410);
PAINT MONO (-4115 5410);
FORCEPROP 2 LASTPIN (-4125 5350) $PN 14
J 0
(-4115 5360);
DISPLAY 0.680851 (-4115 5360);
PAINT MONO (-4115 5360);
FORCEPROP 2 LASTPIN (-4125 5300) $PN 15
J 0
(-4115 5310);
DISPLAY 0.680851 (-4115 5310);
PAINT MONO (-4115 5310);
FORCEPROP 2 LASTPIN (-4125 5250) $PN 16
J 0
(-4115 5260);
DISPLAY 0.680851 (-4115 5260);
PAINT MONO (-4115 5260);
FORCEPROP 2 LASTPIN (-5025 5350) $PN 5
J 2
(-5035 5360);
DISPLAY 0.680851 (-5035 5360);
PAINT MONO (-5035 5360);
FORCEPROP 2 LASTPIN (-5025 5300) $PN 4
J 2
(-5035 5310);
DISPLAY 0.680851 (-5035 5310);
PAINT MONO (-5035 5310);
FORCEPROP 2 LASTPIN (-4125 5100) $PN TH
J 0
(-4115 5110);
DISPLAY 0.680851 (-4115 5110);
PAINT MONO (-4115 5110);
FORCEPROP 2 LASTPIN (-5025 5200) $PN 11
J 2
(-5035 5210);
DISPLAY 0.680851 (-5035 5210);
PAINT MONO (-5035 5210);
FORCEPROP 2 LASTPIN (-5025 5600) $PN 9
J 2
(-5035 5610);
DISPLAY 0.680851 (-5035 5610);
PAINT MONO (-5035 5610);
FORCEPROP 2 LASTPIN (-5025 5100) $PN 12
J 2
(-5035 5110);
DISPLAY 0.680851 (-5035 5110);
PAINT MONO (-5035 5110);
FORCEPROP 2 LASTPIN (-5025 5150) $PN 13
J 2
(-5035 5160);
DISPLAY 0.680851 (-5035 5160);
PAINT MONO (-5035 5160);
FORCEPROP 2 LAST VALUE ISL28022FRZ-T
J 0
(-4850 5975);
DISPLAY 1.021277 (-4850 5975);
FORCEPROP 2 LAST PART_TYPE SMLF
J 0
(-4850 6025);
DISPLAY 1.021277 (-4850 6025);
FORCEPROP 1 LAST MATERIAL IC
J 0
(-4870 5657);
DISPLAY 0.723404 (-4870 5657);
PAINT GREEN (-4870 5657);
FORCEPROP 2 LAST SEC_TYPE 
J 0
(-4850 6075);
DISPLAY 1.021277 (-4850 6075);
DISPLAY INVISIBLE (-4850 6075);
FORCEPROP 1 LAST CDS_LMAN_SYM_OUTLINE -300,300,300,-300
J 0
(-4575 5350);
DISPLAY 0.468085 (-4575 5350);
PAINT GREEN (-4575 5350);
DISPLAY INVISIBLE (-4575 5350);
FORCEPROP 1 LAST NEEDS_NO_SIZE TRUE
J 0
(-4575 5350);
DISPLAY 0.723404 (-4575 5350);
PAINT GREEN (-4575 5350);
DISPLAY INVISIBLE (-4575 5350);
FORCEPROP 2 LAST CDS_LIB pure_quanta
J 0
(-4575 5350);
DISPLAY INVISIBLE (-4575 5350);
FORCEPROP 1 LAST PATH I28
J 0
(-4575 5350);
DISPLAY 0.723404 (-4575 5350);
PAINT GREEN (-4575 5350);
DISPLAY INVISIBLE (-4575 5350);
FORCEPROP 1 LAST PART_NUMBER AL028022003
J 0
(-4870 5784);
DISPLAY 0.723404 (-4870 5784);
PAINT GREEN (-4870 5784);
DISPLAY INVISIBLE (-4870 5784);
FORCEADD Q_RES..2
(-5825 5500);
FORCEPROP 1 LAST LOCATION R6254
J 0
(-5750 5575);
DISPLAY 0.638298 (-5750 5575);
FORCEPROP 0 LAST $SEC 1
J 0
(-5750 5625);
DISPLAY 0.680851 (-5750 5625);
PAINT MONO (-5750 5625);
DISPLAY INVISIBLE (-5750 5625);
FORCEPROP 0 LAST CDS_SEC 1
J 0
(-5750 5625);
DISPLAY 0.680851 (-5750 5625);
DISPLAY INVISIBLE (-5750 5625);
FORCEPROP 1 LASTPIN (-5825 5600) $PN 1
J 0
(-5820 5562);
DISPLAY 0.787234 (-5820 5562);
PAINT MONO (-5820 5562);
FORCEPROP 1 LASTPIN (-5825 5400) $PN 2
J 0
(-5820 5410);
DISPLAY 0.787234 (-5820 5410);
PAINT MONO (-5820 5410);
FORCEPROP 1 LAST MATERIAL CHIP
J 0
(-5750 5475);
DISPLAY 0.404255 (-5750 5475);
FORCEPROP 1 LAST VALUE 0
J 0
(-5750 5550);
DISPLAY 0.404255 (-5750 5550);
FORCEPROP 1 LAST TOLERANCE 5%
J 0
(-5750 5525);
DISPLAY 0.404255 (-5750 5525);
FORCEPROP 1 LAST PACK_TYPE 0402LF
J 0
(-5750 5425);
DISPLAY 0.404255 (-5750 5425);
FORCEPROP 1 LAST WATTAGE 1/16W
J 0
(-5750 5500);
DISPLAY 0.404255 (-5750 5500);
FORCEPROP 2 LAST CDS_LIB pure_quanta
J 0
(-5825 5500);
DISPLAY INVISIBLE (-5825 5500);
FORCEPROP 1 LAST PATH I29
J 0
(-5775 5675);
DISPLAY 0.978723 (-5775 5675);
PAINT WHITE (-5775 5675);
DISPLAY INVISIBLE (-5775 5675);
FORCEPROP 1 LAST PART_NUMBER CS00002JB13
J 0
(-5750 5450);
DISPLAY 0.404255 (-5750 5450);
DISPLAY INVISIBLE (-5750 5450);
FORCEADD UNIVERSAL_GND..1
(-6175 4675);
FORCEPROP 3 LASTPIN (-6175 4725) SIG_NAME GND\g
J 0
(-6165 4735);
DISPLAY 0.659574 (-6165 4735);
PAINT MONO (-6165 4735);
DISPLAY INVISIBLE (-6165 4735);
FORCEPROP 2 LAST CDS_LIB pure_quanta_power
J 0
(-6175 4675);
DISPLAY INVISIBLE (-6175 4675);
FORCEPROP 1 LAST HDL_POWER GND
J 1
(-6150 4600);
DISPLAY 0.872340 (-6150 4600);
PAINT GREEN (-6150 4600);
DISPLAY INVISIBLE (-6150 4600);
FORCEPROP 1 LAST PATH I3
J 0
(-6100 4675);
DISPLAY 0.872340 (-6100 4675);
PAINT AQUA (-6100 4675);
DISPLAY INVISIBLE (-6100 4675);
FORCEADD Q_RES..1
(-7025 5675);
FORCEPROP 1 LAST LOCATION R6250
J 0
(-7250 5675);
DISPLAY 0.638298 (-7250 5675);
FORCEPROP 0 LAST $SEC 1
J 0
(-7200 5725);
DISPLAY 0.680851 (-7200 5725);
PAINT MONO (-7200 5725);
DISPLAY INVISIBLE (-7200 5725);
FORCEPROP 0 LAST CDS_SEC 1
J 0
(-7200 5725);
DISPLAY 0.680851 (-7200 5725);
DISPLAY INVISIBLE (-7200 5725);
FORCEPROP 1 LASTPIN (-7125 5675) $PN 1
J 0
(-7113 5687);
DISPLAY 0.787234 (-7113 5687);
PAINT MONO (-7113 5687);
FORCEPROP 1 LASTPIN (-6925 5675) $PN 2
J 0
(-6963 5687);
DISPLAY 0.787234 (-6963 5687);
PAINT MONO (-6963 5687);
FORCEPROP 1 LAST VALUE 4.7K
J 2
(-6800 5675);
DISPLAY 0.638298 (-6800 5675);
FORCEPROP 1 LAST PACK_TYPE 0402LF
J 0
(-6400 5675);
DISPLAY 0.638298 (-6400 5675);
FORCEPROP 1 LAST MATERIAL CHIP
J 0
(-6525 5675);
DISPLAY 0.638298 (-6525 5675);
FORCEPROP 1 LAST TOLERANCE 1%
J 0
(-6600 5675);
DISPLAY 0.638298 (-6600 5675);
FORCEPROP 1 LAST WATTAGE 1/16W
J 2
(-6625 5675);
DISPLAY 0.638298 (-6625 5675);
FORCEPROP 2 LAST CDS_LIB pure_quanta
J 0
(-7025 5675);
DISPLAY INVISIBLE (-7025 5675);
FORCEPROP 1 LAST PATH I30
J 0
(-7075 5825);
DISPLAY 0.978723 (-7075 5825);
PAINT WHITE (-7075 5825);
DISPLAY INVISIBLE (-7075 5825);
FORCEPROP 1 LAST PART_NUMBER CS24702FB06
J 0
(-7550 5675);
DISPLAY 0.510638 (-7550 5675);
DISPLAY INVISIBLE (-7550 5675);
FORCEADD OFFPAGE..1
(-7450 5200);
FORCEPROP 2 LAST $XR0 268 
J 0
(-7702 5200);
DISPLAY 0.638298 (-7702 5200);
PAINT MONO (-7702 5200);
FORCEPROP 2 LAST CDS_LIB standard
J 0
(-7450 5200);
DISPLAY INVISIBLE (-7450 5200);
FORCEPROP 1 LAST OFFPAGE TRUE
J 0
(-7125 5075);
DISPLAY 0.872340 (-7125 5075);
DISPLAY INVISIBLE (-7125 5075);
FORCEPROP 1 LAST COMMENT_BODY TRUE
J 0
(-7325 5100);
DISPLAY 0.872340 (-7325 5100);
PAINT GREEN (-7325 5100);
DISPLAY INVISIBLE (-7325 5100);
FORCEPROP 2 LAST PATH I31
J 0
(-7400 5275);
DISPLAY 0.680851 (-7400 5275);
DISPLAY INVISIBLE (-7400 5275);
FORCEADD OFFPAGE..3
R 2
(-7425 5300);
FORCEPROP 2 LAST $XR1 236 
J 0
(-7825 5300);
DISPLAY 0.638298 (-7825 5300);
PAINT MONO (-7825 5300);
FORCEPROP 2 LAST $XR0 253 
J 0
(-7705 5300);
DISPLAY 0.638298 (-7705 5300);
PAINT MONO (-7705 5300);
FORCEPROP 2 LAST CDS_LIB standard
J 2
(-7425 5300);
PAINT MONO (-7425 5300);
DISPLAY INVISIBLE (-7425 5300);
FORCEPROP 1 LAST OFFPAGE TRUE
J 2
(-7750 5175);
DISPLAY 0.872340 (-7750 5175);
DISPLAY INVISIBLE (-7750 5175);
FORCEPROP 1 LAST COMMENT_BODY TRUE
J 2
(-7375 5200);
DISPLAY 0.872340 (-7375 5200);
PAINT GREEN (-7375 5200);
DISPLAY INVISIBLE (-7375 5200);
FORCEPROP 2 LAST PATH I5
J 0
(-7700 5350);
DISPLAY 0.680851 (-7700 5350);
DISPLAY INVISIBLE (-7700 5350);
FORCEADD OFFPAGE..1
(-7425 5350);
FORCEPROP 2 LAST $XR1 253 
J 0
(-7797 5350);
DISPLAY 0.638298 (-7797 5350);
PAINT MONO (-7797 5350);
FORCEPROP 2 LAST $XR0 236 
J 0
(-7677 5350);
DISPLAY 0.638298 (-7677 5350);
PAINT MONO (-7677 5350);
FORCEPROP 2 LAST CDS_LIB standard
J 0
(-7425 5350);
DISPLAY INVISIBLE (-7425 5350);
FORCEPROP 1 LAST OFFPAGE TRUE
J 0
(-7100 5225);
DISPLAY 0.872340 (-7100 5225);
DISPLAY INVISIBLE (-7100 5225);
FORCEPROP 1 LAST COMMENT_BODY TRUE
J 0
(-7300 5250);
DISPLAY 0.872340 (-7300 5250);
PAINT GREEN (-7300 5250);
DISPLAY INVISIBLE (-7300 5250);
FORCEPROP 2 LAST PATH I6
J 0
(-7675 5400);
DISPLAY 0.680851 (-7675 5400);
DISPLAY INVISIBLE (-7675 5400);
FORCEADD Q_RES..1
(-6225 5350);
FORCEPROP 1 LAST LOCATION R6252
J 0
(-6475 5350);
DISPLAY 0.787234 (-6475 5350);
FORCEPROP 2 LAST $SEC 1
J 0
(-6275 5550);
DISPLAY 0.680851 (-6275 5550);
PAINT MONO (-6275 5550);
DISPLAY INVISIBLE (-6275 5550);
FORCEPROP 2 LAST CDS_SEC 1
J 0
(-6275 5550);
DISPLAY 1.021277 (-6275 5550);
DISPLAY INVISIBLE (-6275 5550);
FORCEPROP 1 LASTPIN (-6325 5350) $PN 1
J 0
(-6313 5362);
DISPLAY 0.787234 (-6313 5362);
FORCEPROP 1 LASTPIN (-6125 5350) $PN 2
J 0
(-6163 5362);
DISPLAY 0.787234 (-6163 5362);
FORCEPROP 1 LAST MATERIAL CHIP
J 0
(-5925 5350);
DISPLAY 0.510638 (-5925 5350);
FORCEPROP 1 LAST TOLERANCE 1%
J 0
(-6000 5350);
DISPLAY 0.510638 (-6000 5350);
FORCEPROP 1 LAST WATTAGE 1/16W
J 2
(-6100 5425);
DISPLAY 0.510638 (-6100 5425);
FORCEPROP 1 LAST PACK_TYPE 0402LF
J 0
(-6375 5425);
DISPLAY 0.510638 (-6375 5425);
FORCEPROP 1 LAST VALUE 33.2
J 2
(-6025 5350);
DISPLAY 0.510638 (-6025 5350);
FORCEPROP 2 LAST CDS_LIB pure_quanta
J 0
(-6225 5350);
PAINT MONO (-6225 5350);
DISPLAY INVISIBLE (-6225 5350);
FORCEPROP 1 LAST PATH I9
J 0
(-6275 5500);
DISPLAY 0.978723 (-6275 5500);
PAINT WHITE (-6275 5500);
DISPLAY INVISIBLE (-6275 5500);
FORCEPROP 1 LAST PART_NUMBER CS03322FB03
J 0
(-6375 5400);
DISPLAY 0.510638 (-6375 5400);
DISPLAY INVISIBLE (-6375 5400);
FORCEADD DNS..2
(-7000 5575);
PAINT RED (-7000 5575);
FORCEPROP 2 LAST CDS_LIB mstr_misc
J 0
(-7000 5575);
DISPLAY INVISIBLE (-7000 5575);
FORCEPROP 1 LAST COMMENT_BODY TRUE
R 1
J 0
(-6925 5350);
DISPLAY 0.872340 (-6925 5350);
PAINT GREEN (-6925 5350);
DISPLAY INVISIBLE (-6925 5350);
FORCEADD QUANTA_TITLE_BLOCK_C..1
(0 0);
FORCEPROP 0 LAST CDS_CON_LAST_MODIFIED Thu Sep 14 16:12:48 2023
J 0
(-1885 15);
DISPLAY INVISIBLE (-1885 15);
FORCEPROP 1 LAST CUSTOM_TXT_CDS <CON_LAST_MODIFIED>
J 0
(-1885 15);
DISPLAY 0.978723 (-1885 15);
FORCEPROP 2 LAST CUSTOM_TXT_CDS <XR_PAGE_TITLE>
J 0
(-7890 5250);
DISPLAY 0.638298 (-7890 5250);
PAINT PINK (-7890 5250);
DISPLAY INVISIBLE (-7890 5250);
FORCEPROP 1 LAST CUSTOM_TXT_CDS <NAME_2>
J 0
(-3175 50);
FORCEPROP 1 LAST CUSTOM_TXT_CDS <NAME_1>
J 0
(-3175 175);
FORCEPROP 1 LAST CUSTOM_TXT_CDS <Q_NUMBER>
J 0
(-1403 103);
DISPLAY 1.212766 (-1403 103);
FORCEPROP 1 LAST CUSTOM_TXT_CDS <Q_PROJ>
J 0
(-2382 102);
DISPLAY 1.212766 (-2382 102);
FORCEPROP 1 LAST CUSTOM_TXT_CDS <Q_REV>
J 0
(-184 103);
DISPLAY 1.212766 (-184 103);
FORCEPROP 1 LAST CUSTOM_TXT_CDS <CON_PAGE_NUM> OF <CON_TOTAL_PAGES>
J 0
(-446 18);
DISPLAY 0.978723 (-446 18);
FORCEPROP 1 LAST Q_TITLE POWER MONITOR (3/4)
J 0
(-9366 26);
DISPLAY 2.446809 (-9366 26);
PAINT GREEN (-9366 26);
FORCEPROP 2 LAST CDS_LIB pure_quanta
J 0
(0 0);
DISPLAY INVISIBLE (0 0);
FORCEPROP 1 LAST CDS_LMAN_SYM_OUTLINE -9475,6775,100,-125
J 0
(0 0);
DISPLAY 0.468085 (0 0);
PAINT GREEN (0 0);
DISPLAY INVISIBLE (0 0);
FORCEPROP 2 LAST PAGE_BORDER TRUE
J 0
(-7890 5250);
DISPLAY 0.638298 (-7890 5250);
PAINT PINK (-7890 5250);
DISPLAY INVISIBLE (-7890 5250);
FORCEPROP 2 LAST CDS_XR_PAGE_TITLE CR-272 : @T6G_MB_LIB.T6G(SCH_1):PAGE272
J 0
(-7890 5250);
DISPLAY 0.638298 (-7890 5250);
PAINT PINK (-7890 5250);
DISPLAY INVISIBLE (-7890 5250);
FORCEPROP 1 LAST Q_DEPT BU9
J 1
(-3763 49);
DISPLAY 1.957447 (-3763 49);
PAINT GREEN (-3763 49);
DISPLAY INVISIBLE (-3763 49);
FORCEPROP 1 LAST COMMENT_BODY TRUE
J 0
(12 -13);
DISPLAY 0.978723 (12 -13);
PAINT GREEN (12 -13);
DISPLAY INVISIBLE (12 -13);
FORCEADD BOM_NOTE..1
(-8925 4425);
FORCEPROP 0 LAST S1 POWER MONITOR WILL CHANGE TO AL000230001
J 0
(-9075 4275);
DISPLAY 1.595745 (-9075 4275);
PAINT SKYBLUE (-9075 4275);
FORCEPROP 2 LAST CDS_LIB pure_quanta_power
J 0
(-8925 4425);
DISPLAY INVISIBLE (-8925 4425);
FORCEPROP 1 LAST COMMENT_BODY TRUE
J 0
(-8900 4525);
DISPLAY 0.978723 (-8900 4525);
DISPLAY INVISIBLE (-8900 4525);
WIRE 16 -1 (-5325 5850)(-5325 5775);
WIRE 16 -1 (-3375 6150)(-3375 6200);
WIRE 16 -1 (-6175 4875)(-6175 4725);
WIRE 16 -1 (-7125 5675)(-7575 5675);
WIRE 16 -1 (-7575 5675)(-7575 5625);
WIRE 16 -1 (-7575 5625)(-7125 5625);
WIRE 16 -1 (-7575 5525)(-7575 5625);
WIRE 16 -1 (-4125 5150)(-4000 5150);
WIRE 16 -1 (-4000 5150)(-4000 5100);
WIRE 16 -1 (-4125 5100)(-4000 5100);
WIRE 16 -1 (-4000 5100)(-4000 4750);
WIRE 16 -1 (-5100 6175)(-5075 6175);
WIRE 16 -1 (-5325 6175)(-5100 6175);
WIRE 16 -1 (-5100 6175)(-5100 5600);
WIRE 16 -1 (-5075 6300)(-5075 6175);
WIRE 16 -1 (-5100 5600)(-5025 5600);
WIRE 16 -1 (-5325 6050)(-5325 6175);
WIRE 16 -1 (-5025 5100)(-5425 5100);
FORCEPROP 2 LAST SIG_NAME NC_HSC_TYPE_VINM
J 0
(-5610 5110);
DISPLAY 0.680851 (-5610 5110);
FORCEPROP 2 LASTPROP $XRERR UNIQUE?
J 0
(-5665 5100);
DISPLAY 0.638298 (-5665 5100);
PAINT MONO (-5665 5100);
DISPLAY INVISIBLE (-5665 5100);
WIRE 16 -1 (-7400 5200)(-6175 5200);
FORCEPROP 2 LAST SIG_NAME HSC_TYPE_ADC
J 0
(-6735 5210);
DISPLAY 0.680851 (-6735 5210);
WIRE 16 -1 (-5025 5200)(-6175 5200);
WIRE 16 -1 (-6175 5075)(-6175 5200);
WIRE 16 -1 (-7375 5300)(-6325 5300);
FORCEPROP 2 LAST SIG_NAME SMB_LM75_0_3V3AUX_SDA
J 0
(-7260 5310);
DISPLAY 0.680851 (-7260 5310);
WIRE 16 -1 (-7375 5350)(-6325 5350);
FORCEPROP 2 LAST SIG_NAME SMB_LM75_0_3V3AUX_SCL
J 0
(-7260 5360);
DISPLAY 0.680851 (-7260 5360);
WIRE 16 -1 (-6125 5350)(-5025 5350);
FORCEPROP 2 LAST SIG_NAME SMB_HSC_TYPE_ADC_SCL
J 0
(-5785 5350);
DISPLAY 0.680851 (-5785 5350);
PAINT WHITE (-5785 5350);
FORCEPROP 2 LASTPROP $XRERR UNIQUE?
J 0
(-6025 5350);
DISPLAY 0.638298 (-6025 5350);
PAINT MONO (-6025 5350);
DISPLAY INVISIBLE (-6025 5350);
WIRE 16 -1 (-4125 5250)(-3500 5250);
FORCEPROP 2 LAST SIG_NAME NC_HSC_TYPE_NC5
J 0
(-3985 5260);
DISPLAY 0.638298 (-3985 5260);
PAINT WHITE (-3985 5260);
FORCEPROP 2 LASTPROP $XRERR UNIQUE?
J 0
(-3470 5250);
DISPLAY 0.638298 (-3470 5250);
PAINT MONO (-3470 5250);
DISPLAY INVISIBLE (-3470 5250);
WIRE 16 -1 (-4125 5300)(-3500 5300);
FORCEPROP 2 LAST SIG_NAME NC_HSC_TYPE_NC4
J 0
(-3985 5310);
DISPLAY 0.638298 (-3985 5310);
PAINT WHITE (-3985 5310);
FORCEPROP 2 LASTPROP $XRERR UNIQUE?
J 0
(-3470 5300);
DISPLAY 0.638298 (-3470 5300);
PAINT MONO (-3470 5300);
DISPLAY INVISIBLE (-3470 5300);
WIRE 16 -1 (-4125 5350)(-3500 5350);
FORCEPROP 2 LAST SIG_NAME NC_HSC_TYPE_NC3
J 0
(-3985 5360);
DISPLAY 0.638298 (-3985 5360);
PAINT WHITE (-3985 5360);
FORCEPROP 2 LASTPROP $XRERR UNIQUE?
J 0
(-3470 5350);
DISPLAY 0.638298 (-3470 5350);
PAINT MONO (-3470 5350);
DISPLAY INVISIBLE (-3470 5350);
WIRE 16 -1 (-4125 5400)(-3500 5400);
FORCEPROP 2 LAST SIG_NAME NC_HSC_TYPE_NC2
J 0
(-3985 5410);
DISPLAY 0.638298 (-3985 5410);
PAINT WHITE (-3985 5410);
FORCEPROP 2 LASTPROP $XRERR UNIQUE?
J 0
(-3470 5400);
DISPLAY 0.638298 (-3470 5400);
PAINT MONO (-3470 5400);
DISPLAY INVISIBLE (-3470 5400);
WIRE 16 -1 (-4125 5450)(-3500 5450);
FORCEPROP 2 LAST SIG_NAME NC_HSC_TYPE_NC1
J 0
(-4010 5460);
DISPLAY 0.638298 (-4010 5460);
PAINT WHITE (-4010 5460);
FORCEPROP 2 LASTPROP $XRERR UNIQUE?
J 0
(-3470 5450);
DISPLAY 0.638298 (-3470 5450);
PAINT MONO (-3470 5450);
DISPLAY INVISIBLE (-3470 5450);
WIRE 16 -1 (-4125 5500)(-3500 5500);
FORCEPROP 2 LAST SIG_NAME NC_HSC_TYPE_NC0
J 0
(-3985 5510);
DISPLAY 0.638298 (-3985 5510);
PAINT WHITE (-3985 5510);
FORCEPROP 2 LASTPROP $XRERR UNIQUE?
J 0
(-3470 5500);
DISPLAY 0.638298 (-3470 5500);
PAINT MONO (-3470 5500);
DISPLAY INVISIBLE (-3470 5500);
WIRE 16 -1 (-4125 5600)(-3375 5600);
FORCEPROP 2 LAST SIG_NAME HSC_TYPE_ADC_ALERT
J 0
(-3985 5610);
DISPLAY 0.638298 (-3985 5610);
PAINT WHITE (-3985 5610);
FORCEPROP 2 LASTPROP $XRERR UNIQUE?
J 0
(-4225 5610);
DISPLAY 0.638298 (-4225 5610);
PAINT MONO (-4225 5610);
DISPLAY INVISIBLE (-4225 5610);
WIRE 16 -1 (-3375 5950)(-3375 5600);
WIRE 16 -1 (-5425 5150)(-5025 5150);
FORCEPROP 2 LAST SIG_NAME NC_HSC_TYPE_VINP
J 0
(-5610 5160);
DISPLAY 0.680851 (-5610 5160);
FORCEPROP 2 LASTPROP $XRERR UNIQUE?
J 0
(-5665 5150);
DISPLAY 0.638298 (-5665 5150);
PAINT MONO (-5665 5150);
DISPLAY INVISIBLE (-5665 5150);
WIRE 16 -1 (-6125 5300)(-5825 5300);
WIRE 16 -1 (-5825 5300)(-5025 5300);
FORCEPROP 2 LAST SIG_NAME SMB_HSC_TYPE_ADC_SDA
J 0
(-5785 5310);
DISPLAY 0.680851 (-5785 5310);
PAINT WHITE (-5785 5310);
FORCEPROP 2 LASTPROP $XRERR UNIQUE?
J 0
(-6025 5310);
DISPLAY 0.638298 (-6025 5310);
PAINT MONO (-6025 5310);
DISPLAY INVISIBLE (-6025 5310);
WIRE 16 -1 (-5825 5400)(-5825 5300);
WIRE 16 -1 (-5175 5450)(-5025 5450);
WIRE 16 -1 (-5175 5625)(-5175 5450);
WIRE 16 -1 (-5175 5625)(-5825 5625);
FORCEPROP 2 LAST SIG_NAME HSC_TYPE_ADC_A0
J 0
(-5810 5625);
DISPLAY 0.638298 (-5810 5625);
PAINT WHITE (-5810 5625);
FORCEPROP 2 LASTPROP $XRERR UNIQUE?
J 0
(-6050 5625);
DISPLAY 0.638298 (-6050 5625);
PAINT MONO (-6050 5625);
DISPLAY INVISIBLE (-6050 5625);
WIRE 16 -1 (-5825 5600)(-5825 5625);
WIRE 16 -1 (-6925 5625)(-5825 5625);
WIRE 16 -1 (-5150 5675)(-5150 5500);
WIRE 16 -1 (-5150 5675)(-6925 5675);
FORCEPROP 2 LAST SIG_NAME HSC_TYPE_ADC_A1
J 0
(-5810 5700);
DISPLAY 0.638298 (-5810 5700);
PAINT WHITE (-5810 5700);
FORCEPROP 2 LASTPROP $XRERR UNIQUE?
J 0
(-6050 5700);
DISPLAY 0.638298 (-6050 5700);
PAINT MONO (-6050 5700);
DISPLAY INVISIBLE (-6050 5700);
WIRE 16 -1 (-5150 5500)(-5025 5500);
DOT 1 (-7575 5625);
DOT 1 (-6175 5200);
DOT 1 (-5825 5300);
DOT 1 (-5825 5625);
DOT 1 (-5100 6175);
DOT 1 (-4000 5100);
FORCENOTE
0X42 (7-BIT)
(-4950 4775) 0;
DISPLAY LEFT (-4950 4775);
DISPLAY 1.340425 (-4950 4775);
PAINT WHITE (-4950 4775);
FORCENOTE
ADDRESS : 0X84 (8-BIT)
(-5575 4875) 0;
DISPLAY LEFT (-5575 4875);
DISPLAY 1.340425 (-5575 4875);
PAINT WHITE (-5575 4875);
QUIT
